(kicad_pcb
	(version 20260206)
	(generator "pcbnew")
	(generator_version "10.0")
	(general
		(thickness 1.6)
		(legacy_teardrops no)
	)
	(paper "A4")
	(title_block
		(title "Bryce Canyon_SCC_16316-1_OCP.brd")
		(comment 1 "Bryce Canyon / footprints 155-161 of 1561")
	)
	(layers
		(0 "F.Cu" signal "TOP")
		(4 "In1.Cu" signal "L2GND")
		(6 "In2.Cu" signal "L3")
		(8 "In3.Cu" signal "L4VCC")
		(10 "In4.Cu" signal "L5VCC")
		(12 "In5.Cu" signal "L6")
		(14 "In6.Cu" signal "L7GND")
		(2 "B.Cu" signal "BOTTOM")
		(9 "F.Adhes" user "F.Adhesive")
		(11 "B.Adhes" user "B.Adhesive")
		(13 "F.Paste" user "Package Geometry/Pastemask Top")
		(15 "B.Paste" user "Package Geometry/Pastemask Bottom")
		(5 "F.SilkS" user "Ref Des/Silkscreen Top")
		(7 "B.SilkS" user "Ref Des/Silkscreen Bottom")
		(1 "F.Mask" user "Board Geometry/Soldermask Top")
		(3 "B.Mask" user "Board Geometry/Soldermask Bottom")
		(17 "Dwgs.User" user "User.Drawings")
		(19 "Cmts.User" user "User.Comments")
		(21 "Eco1.User" user "User.Eco1")
		(23 "Eco2.User" user "User.Eco2")
		(25 "Edge.Cuts" user "Board Geometry/Outline")
		(27 "Margin" user)
		(31 "F.CrtYd" user "Package Geometry/Place Bound Top")
		(29 "B.CrtYd" user "Package Geometry/Place Bound Bottom")
		(35 "F.Fab" user "Ref Des/Assembly Top")
		(33 "B.Fab" user "Ref Des/Assembly Bottom")
	)
	(footprint ""
		(layer "F.Cu")
		(at 179.1208 -107.78744)
		(property "Reference" "Q22"
			(at 0 0 0)
			(layer "F.SilkS")
			(hide yes)
			(effects
				(font
					(size 1.27 1.27)
				)
			)
		)
		(property "Value" "2N7002K-1-GP"
			(at 0.127 -8.9662 0)
			(unlocked yes)
			(layer "F.Fab")
			(hide yes)
			(effects
				(font
					(size 1.016 1.016)
					(thickness 0.1524)
				)
			)
		)
		(property "Device Type" "SOT23DGS2D4H44"
			(at 0.127 -10.4902 0)
			(unlocked yes)
			(layer "F.Fab")
			(hide yes)
			(effects
				(font
					(size 1.016 1.016)
					(thickness 0.1524)
				)
			)
		)
		(duplicate_pad_numbers_are_jumpers no)
		(fp_line
			(start -1.651 -1.778)
			(end -1.651 1.778)
			(stroke
				(width 0.1524)
				(type default)
			)
			(layer "F.SilkS")
		)
		(fp_line
			(start -1.651 1.778)
			(end 1.651 1.778)
			(stroke
				(width 0.1524)
				(type default)
			)
			(layer "F.SilkS")
		)
		(fp_line
			(start 1.651 -1.778)
			(end -1.651 -1.778)
			(stroke
				(width 0.1524)
				(type default)
			)
			(layer "F.SilkS")
		)
		(fp_line
			(start 1.651 1.778)
			(end 1.651 -1.778)
			(stroke
				(width 0.1524)
				(type default)
			)
			(layer "F.SilkS")
		)
		(fp_poly
			(pts
				(xy -1.778 1.8796) (xy -1.778 -1.8796) (xy 1.778 -1.8796) (xy 1.778 1.8796)
			)
			(stroke
				(width 0)
				(type default)
			)
			(fill no)
			(layer "F.CrtYd")
		)
		(fp_poly
			(pts
				(xy -1.778 1.8796) (xy -1.778 -1.8796) (xy 1.778 -1.8796) (xy 1.778 1.8796)
			)
			(stroke
				(width 0)
				(type default)
			)
			(fill no)
			(layer "F.Fab")
		)
		(pad "D" smd custom
			(at 0 -0.9525)
			(size 0.1905 0.1905)
			(layers "F.Cu" "F.Mask" "F.Paste")
			(net "Q22_D")
			(options
				(clearance outline)
				(anchor circle)
			)
			(primitives
				(gr_poly
					(pts
						(arc
							(start -0.1778 0.5715)
							(mid -0.321484 0.511984)
							(end -0.381 0.3683)
						)
						(arc
							(start -0.381 -0.3683)
							(mid -0.321484 -0.511984)
							(end -0.1778 -0.5715)
						)
						(arc
							(start 0.1778 -0.5715)
							(mid 0.321484 -0.511984)
							(end 0.381 -0.3683)
						)
						(arc
							(start 0.381 0.3683)
							(mid 0.321484 0.511984)
							(end 0.1778 0.5715)
						)
					)
					(width 0)
					(fill yes)
				)
			)
		)
		(pad "G" smd custom
			(at -0.98425 0.9525)
			(size 0.1905 0.1905)
			(layers "F.Cu" "F.Mask" "F.Paste")
			(net "P12V_STBY_Q12_G")
			(options
				(clearance outline)
				(anchor circle)
			)
			(primitives
				(gr_poly
					(pts
						(arc
							(start -0.1778 0.5715)
							(mid -0.321484 0.511984)
							(end -0.381 0.3683)
						)
						(arc
							(start -0.381 -0.3683)
							(mid -0.321484 -0.511984)
							(end -0.1778 -0.5715)
						)
						(arc
							(start 0.1778 -0.5715)
							(mid 0.321484 -0.511984)
							(end 0.381 -0.3683)
						)
						(arc
							(start 0.381 0.3683)
							(mid 0.321484 0.511984)
							(end 0.1778 0.5715)
						)
					)
					(width 0)
					(fill yes)
				)
			)
		)
		(pad "S" smd custom
			(at 0.98425 0.9525)
			(size 0.1905 0.1905)
			(layers "F.Cu" "F.Mask" "F.Paste")
			(net "GND")
			(options
				(clearance outline)
				(anchor circle)
			)
			(primitives
				(gr_poly
					(pts
						(arc
							(start -0.1778 0.5715)
							(mid -0.321484 0.511984)
							(end -0.381 0.3683)
						)
						(arc
							(start -0.381 -0.3683)
							(mid -0.321484 -0.511984)
							(end -0.1778 -0.5715)
						)
						(arc
							(start 0.1778 -0.5715)
							(mid 0.321484 -0.511984)
							(end 0.381 -0.3683)
						)
						(arc
							(start 0.381 0.3683)
							(mid 0.321484 0.511984)
							(end 0.1778 0.5715)
						)
					)
					(width 0)
					(fill yes)
				)
			)
		)
	)
	(footprint ""
		(layer "F.Cu")
		(at 59.055 -97.5868 -90)
		(property "Reference" "C656"
			(at 0 0 270)
			(layer "F.SilkS")
			(hide yes)
			(effects
				(font
					(size 1.27 1.27)
				)
			)
		)
		(property "Value" "SCD1U50V3KX-GP"
			(at 0 -2.8194 270)
			(unlocked yes)
			(layer "F.Fab")
			(hide yes)
			(effects
				(font
					(size 1.016 1.016)
					(thickness 0.1524)
				)
			)
		)
		(property "Device Type" "C603H36"
			(at 0 -4.3434 270)
			(unlocked yes)
			(layer "F.Fab")
			(hide yes)
			(effects
				(font
					(size 1.016 1.016)
					(thickness 0.1524)
				)
			)
		)
		(duplicate_pad_numbers_are_jumpers no)
		(fp_line
			(start 0.508 0)
			(end -0.508 0)
			(stroke
				(width 0.2032)
				(type default)
			)
			(layer "F.SilkS")
		)
		(fp_rect
			(start -0.5842 1.3335)
			(end 0.5842 -1.3335)
			(stroke
				(width 0)
				(type default)
			)
			(fill no)
			(layer "F.CrtYd")
		)
		(fp_rect
			(start -0.5842 1.3335)
			(end 0.5842 -1.3335)
			(stroke
				(width 0)
				(type default)
			)
			(fill no)
			(layer "F.Fab")
		)
		(pad "1" smd custom
			(at 0 -0.762 270)
			(size 0.2159 0.2159)
			(layers "F.Cu" "F.Mask" "F.Paste")
			(net "P12V_STBY_VIN_U10")
			(options
				(clearance outline)
				(anchor circle)
			)
			(primitives
				(gr_poly
					(pts
						(arc
							(start -0.3302 -0.4318)
							(mid -0.402042 -0.402042)
							(end -0.4318 -0.3302)
						)
						(arc
							(start -0.4318 0.3302)
							(mid -0.402042 0.402042)
							(end -0.3302 0.4318)
						)
						(arc
							(start 0.3302 0.4318)
							(mid 0.402042 0.402042)
							(end 0.4318 0.3302)
						)
						(arc
							(start 0.4318 -0.3302)
							(mid 0.402042 -0.402042)
							(end 0.3302 -0.4318)
						)
					)
					(width 0)
					(fill yes)
				)
			)
		)
		(pad "2" smd custom
			(at 0 0.762 270)
			(size 0.2159 0.2159)
			(layers "F.Cu" "F.Mask" "F.Paste")
			(net "GND")
			(options
				(clearance outline)
				(anchor circle)
			)
			(primitives
				(gr_poly
					(pts
						(arc
							(start -0.3302 -0.4318)
							(mid -0.402042 -0.402042)
							(end -0.4318 -0.3302)
						)
						(arc
							(start -0.4318 0.3302)
							(mid -0.402042 0.402042)
							(end -0.3302 0.4318)
						)
						(arc
							(start 0.3302 0.4318)
							(mid 0.402042 0.402042)
							(end 0.4318 0.3302)
						)
						(arc
							(start 0.4318 -0.3302)
							(mid 0.402042 -0.402042)
							(end 0.3302 -0.4318)
						)
					)
					(width 0)
					(fill yes)
				)
			)
		)
	)
	(footprint ""
		(layer "F.Cu")
		(at 74.914252 -78.140306 180)
		(property "Reference" "U118"
			(at 0 0 180)
			(layer "F.SilkS")
			(hide yes)
			(effects
				(font
					(size 1.27 1.27)
				)
			)
		)
		(property "Value" "NX3L1G66GW-GP"
			(at -2.3368 -8.6868 180)
			(unlocked yes)
			(layer "F.Fab")
			(hide yes)
			(effects
				(font
					(size 1.016 1.016)
					(thickness 0.1524)
				)
			)
		)
		(property "Device Type" "SC70-5H44"
			(at -2.3114 -10.414 180)
			(unlocked yes)
			(layer "F.Fab")
			(hide yes)
			(effects
				(font
					(size 1.016 1.016)
					(thickness 0.1524)
				)
			)
		)
		(duplicate_pad_numbers_are_jumpers no)
		(fp_line
			(start 1.3843 -1.8034)
			(end 1.3843 -1.1176)
			(stroke
				(width 0.3302)
				(type default)
			)
			(layer "F.SilkS")
		)
		(fp_line
			(start 1.27 1.7018)
			(end -1.27 1.7018)
			(stroke
				(width 0.1524)
				(type default)
			)
			(layer "F.SilkS")
		)
		(fp_line
			(start 1.27 -1.7018)
			(end 1.27 1.7018)
			(stroke
				(width 0.1524)
				(type default)
			)
			(layer "F.SilkS")
		)
		(fp_line
			(start 0.6604 -1.8034)
			(end 1.3843 -1.8034)
			(stroke
				(width 0.3302)
				(type default)
			)
			(layer "F.SilkS")
		)
		(fp_line
			(start -1.27 1.7018)
			(end -1.27 -1.7018)
			(stroke
				(width 0.1524)
				(type default)
			)
			(layer "F.SilkS")
		)
		(fp_line
			(start -1.27 -1.7018)
			(end 1.27 -1.7018)
			(stroke
				(width 0.1524)
				(type default)
			)
			(layer "F.SilkS")
		)
		(fp_rect
			(start -1.524 1.9558)
			(end 1.524 -1.9558)
			(stroke
				(width 0)
				(type default)
			)
			(fill no)
			(layer "F.CrtYd")
		)
		(fp_poly
			(pts
				(xy -1.524 -1.9558) (xy 1.524 -1.9558) (xy 1.524 1.9558) (xy -1.524 1.9558)
			)
			(stroke
				(width 0)
				(type default)
			)
			(fill no)
			(layer "F.Fab")
		)
		(pad "1" smd rect
			(at 0.65024 -0.8255 180)
			(size 0.4064 1.2192)
			(layers "F.Cu" "F.Mask" "F.Paste")
			(net "I2C_EXP_IOC_SCL8")
		)
		(pad "2" smd rect
			(at 0 -0.8255 180)
			(size 0.4064 1.2192)
			(layers "F.Cu" "F.Mask" "F.Paste")
			(net "I2C_IOC_4_R_SCL")
		)
		(pad "3" smd rect
			(at -0.65024 -0.8255 180)
			(size 0.4064 1.2192)
			(layers "F.Cu" "F.Mask" "F.Paste")
			(net "GND")
		)
		(pad "4" smd rect
			(at -0.65024 0.8255 180)
			(size 0.4064 1.2192)
			(layers "F.Cu" "F.Mask" "F.Paste")
			(net "PCIE_COMP_TO_SCC_RST_R_0")
		)
		(pad "5" smd rect
			(at 0.65024 0.8255 180)
			(size 0.4064 1.2192)
			(layers "F.Cu" "F.Mask" "F.Paste")
			(net "U118_VCC")
		)
	)
	(footprint ""
		(layer "F.Cu")
		(at 157.6324 -110.9218)
		(property "Reference" "C696"
			(at 0 0 0)
			(layer "F.SilkS")
			(hide yes)
			(effects
				(font
					(size 1.27 1.27)
				)
			)
		)
		(property "Value" "SCD1U50V3KX-GP"
			(at 0 -2.8194 0)
			(unlocked yes)
			(layer "F.Fab")
			(hide yes)
			(effects
				(font
					(size 1.016 1.016)
					(thickness 0.1524)
				)
			)
		)
		(property "Device Type" "C603H36"
			(at 0 -4.3434 0)
			(unlocked yes)
			(layer "F.Fab")
			(hide yes)
			(effects
				(font
					(size 1.016 1.016)
					(thickness 0.1524)
				)
			)
		)
		(duplicate_pad_numbers_are_jumpers no)
		(fp_line
			(start 0.508 0)
			(end -0.508 0)
			(stroke
				(width 0.2032)
				(type default)
			)
			(layer "F.SilkS")
		)
		(fp_rect
			(start -0.5842 1.3335)
			(end 0.5842 -1.3335)
			(stroke
				(width 0)
				(type default)
			)
			(fill no)
			(layer "F.CrtYd")
		)
		(fp_rect
			(start -0.5842 1.3335)
			(end 0.5842 -1.3335)
			(stroke
				(width 0)
				(type default)
			)
			(fill no)
			(layer "F.Fab")
		)
		(pad "1" smd custom
			(at 0 -0.762)
			(size 0.2159 0.2159)
			(layers "F.Cu" "F.Mask" "F.Paste")
			(net "P12V_STBY_VIN_U11")
			(options
				(clearance outline)
				(anchor circle)
			)
			(primitives
				(gr_poly
					(pts
						(arc
							(start -0.3302 -0.4318)
							(mid -0.402042 -0.402042)
							(end -0.4318 -0.3302)
						)
						(arc
							(start -0.4318 0.3302)
							(mid -0.402042 0.402042)
							(end -0.3302 0.4318)
						)
						(arc
							(start 0.3302 0.4318)
							(mid 0.402042 0.402042)
							(end 0.4318 0.3302)
						)
						(arc
							(start 0.4318 -0.3302)
							(mid 0.402042 -0.402042)
							(end 0.3302 -0.4318)
						)
					)
					(width 0)
					(fill yes)
				)
			)
		)
		(pad "2" smd custom
			(at 0 0.762)
			(size 0.2159 0.2159)
			(layers "F.Cu" "F.Mask" "F.Paste")
			(net "GND")
			(options
				(clearance outline)
				(anchor circle)
			)
			(primitives
				(gr_poly
					(pts
						(arc
							(start -0.3302 -0.4318)
							(mid -0.402042 -0.402042)
							(end -0.4318 -0.3302)
						)
						(arc
							(start -0.4318 0.3302)
							(mid -0.402042 0.402042)
							(end -0.3302 0.4318)
						)
						(arc
							(start 0.3302 0.4318)
							(mid 0.402042 0.402042)
							(end 0.4318 0.3302)
						)
						(arc
							(start 0.4318 -0.3302)
							(mid 0.402042 -0.402042)
							(end 0.3302 -0.4318)
						)
					)
					(width 0)
					(fill yes)
				)
			)
		)
	)
	(footprint ""
		(layer "F.Cu")
		(at 7.5946 -52.1462)
		(property "Reference" "R543"
			(at 0 0 0)
			(layer "F.SilkS")
			(hide yes)
			(effects
				(font
					(size 1.27 1.27)
				)
			)
		)
		(property "Value" "11KR2F-L-GP"
			(at 0.064008 -3.993896 0)
			(unlocked yes)
			(layer "F.Fab")
			(hide yes)
			(effects
				(font
					(size 1.016 1.016)
					(thickness 0.1524)
				)
			)
		)
		(property "Device Type" "R402H16"
			(at 0.064008 -5.517896 0)
			(unlocked yes)
			(layer "F.Fab")
			(hide yes)
			(effects
				(font
					(size 1.016 1.016)
					(thickness 0.1524)
				)
			)
		)
		(duplicate_pad_numbers_are_jumpers no)
		(fp_line
			(start -0.508 -0.9398)
			(end -0.508 0.9398)
			(stroke
				(width 0.1524)
				(type default)
			)
			(layer "F.SilkS")
		)
		(fp_line
			(start 0.508 -0.9398)
			(end -0.508 -0.9398)
			(stroke
				(width 0.1524)
				(type default)
			)
			(layer "F.SilkS")
		)
		(fp_rect
			(start -0.508 0.9398)
			(end 0.508 -0.9398)
			(stroke
				(width 0)
				(type default)
			)
			(fill no)
			(layer "F.CrtYd")
		)
		(fp_rect
			(start -0.508 0.9398)
			(end 0.508 -0.9398)
			(stroke
				(width 0)
				(type default)
			)
			(fill no)
			(layer "F.Fab")
		)
		(pad "1" smd custom
			(at 0 -0.4445)
			(size 0.1397 0.1397)
			(layers "F.Cu" "F.Mask" "F.Paste")
			(net "MB0_P12V_PWGIN_R")
			(options
				(clearance outline)
				(anchor circle)
			)
			(primitives
				(gr_poly
					(pts
						(arc
							(start -0.1778 -0.2794)
							(mid -0.249642 -0.249642)
							(end -0.2794 -0.1778)
						)
						(arc
							(start -0.2794 0.1778)
							(mid -0.249642 0.249642)
							(end -0.1778 0.2794)
						)
						(arc
							(start 0.1778 0.2794)
							(mid 0.249642 0.249642)
							(end 0.2794 0.1778)
						)
						(arc
							(start 0.2794 -0.1778)
							(mid 0.249642 -0.249642)
							(end 0.1778 -0.2794)
						)
					)
					(width 0)
					(fill yes)
				)
			)
		)
		(pad "2" smd custom
			(at 0 0.4445)
			(size 0.1397 0.1397)
			(layers "F.Cu" "F.Mask" "F.Paste")
			(net "AGND_CURRENT_MON")
			(options
				(clearance outline)
				(anchor circle)
			)
			(primitives
				(gr_poly
					(pts
						(arc
							(start -0.1778 -0.2794)
							(mid -0.249642 -0.249642)
							(end -0.2794 -0.1778)
						)
						(arc
							(start -0.2794 0.1778)
							(mid -0.249642 0.249642)
							(end -0.1778 0.2794)
						)
						(arc
							(start 0.1778 0.2794)
							(mid 0.249642 0.249642)
							(end 0.2794 0.1778)
						)
						(arc
							(start 0.2794 -0.1778)
							(mid 0.249642 -0.249642)
							(end 0.1778 -0.2794)
						)
					)
					(width 0)
					(fill yes)
				)
			)
		)
	)
	(footprint ""
		(layer "F.Cu")
		(at 94.1832 -72.1106 -90)
		(property "Reference" "R112"
			(at 0 0 270)
			(layer "F.SilkS")
			(hide yes)
			(effects
				(font
					(size 1.27 1.27)
				)
			)
		)
		(property "Value" "4K75R2F-1-GP"
			(at 0.064008 -3.993896 270)
			(unlocked yes)
			(layer "F.Fab")
			(hide yes)
			(effects
				(font
					(size 1.016 1.016)
					(thickness 0.1524)
				)
			)
		)
		(property "Device Type" "R402H16"
			(at 0.064008 -5.517896 270)
			(unlocked yes)
			(layer "F.Fab")
			(hide yes)
			(effects
				(font
					(size 1.016 1.016)
					(thickness 0.1524)
				)
			)
		)
		(duplicate_pad_numbers_are_jumpers no)
		(fp_line
			(start -0.508 -0.9398)
			(end -0.508 0.9398)
			(stroke
				(width 0.1524)
				(type default)
			)
			(layer "F.SilkS")
		)
		(fp_line
			(start 0.508 -0.9398)
			(end -0.508 -0.9398)
			(stroke
				(width 0.1524)
				(type default)
			)
			(layer "F.SilkS")
		)
		(fp_rect
			(start -0.508 0.9398)
			(end 0.508 -0.9398)
			(stroke
				(width 0)
				(type default)
			)
			(fill no)
			(layer "F.CrtYd")
		)
		(fp_rect
			(start -0.508 0.9398)
			(end 0.508 -0.9398)
			(stroke
				(width 0)
				(type default)
			)
			(fill no)
			(layer "F.Fab")
		)
		(pad "1" smd custom
			(at 0 -0.4445 270)
			(size 0.1397 0.1397)
			(layers "F.Cu" "F.Mask" "F.Paste")
			(net "EXP_CPU_MODE_0")
			(options
				(clearance outline)
				(anchor circle)
			)
			(primitives
				(gr_poly
					(pts
						(arc
							(start -0.1778 -0.2794)
							(mid -0.249642 -0.249642)
							(end -0.2794 -0.1778)
						)
						(arc
							(start -0.2794 0.1778)
							(mid -0.249642 0.249642)
							(end -0.1778 0.2794)
						)
						(arc
							(start 0.1778 0.2794)
							(mid 0.249642 0.249642)
							(end 0.2794 0.1778)
						)
						(arc
							(start 0.2794 -0.1778)
							(mid 0.249642 -0.249642)
							(end 0.1778 -0.2794)
						)
					)
					(width 0)
					(fill yes)
				)
			)
		)
		(pad "2" smd custom
			(at 0 0.4445 270)
			(size 0.1397 0.1397)
			(layers "F.Cu" "F.Mask" "F.Paste")
			(net "GND")
			(options
				(clearance outline)
				(anchor circle)
			)
			(primitives
				(gr_poly
					(pts
						(arc
							(start -0.1778 -0.2794)
							(mid -0.249642 -0.249642)
							(end -0.2794 -0.1778)
						)
						(arc
							(start -0.2794 0.1778)
							(mid -0.249642 0.249642)
							(end -0.1778 0.2794)
						)
						(arc
							(start 0.1778 0.2794)
							(mid 0.249642 0.249642)
							(end 0.2794 0.1778)
						)
						(arc
							(start 0.2794 -0.1778)
							(mid 0.249642 -0.249642)
							(end 0.1778 -0.2794)
						)
					)
					(width 0)
					(fill yes)
				)
			)
		)
	)
	(footprint ""
		(layer "F.Cu")
		(at 53.1876 -73.1012 -90)
		(property "Reference" "C562"
			(at 0 0 270)
			(layer "F.SilkS")
			(hide yes)
			(effects
				(font
					(size 1.27 1.27)
				)
			)
		)
		(property "Value" "SCD1U16V2KX-3GP"
			(at 1.1811 -2.7051 270)
			(unlocked yes)
			(layer "F.Fab")
			(hide yes)
			(effects
				(font
					(size 1.016 1.016)
					(thickness 0.1524)
				)
			)
		)
		(property "Device Type" "C402H22"
			(at 1.1811 -4.2291 270)
			(unlocked yes)
			(layer "F.Fab")
			(hide yes)
			(effects
				(font
					(size 1.016 1.016)
					(thickness 0.1524)
				)
			)
		)
		(duplicate_pad_numbers_are_jumpers no)
		(fp_rect
			(start -0.4318 0.9525)
			(end 0.4318 -0.9525)
			(stroke
				(width 0)
				(type default)
			)
			(fill no)
			(layer "F.CrtYd")
		)
		(fp_rect
			(start -0.4318 0.9525)
			(end 0.4318 -0.9525)
			(stroke
				(width 0)
				(type default)
			)
			(fill no)
			(layer "F.Fab")
		)
		(pad "1" smd custom
			(at 0 -0.4445 270)
			(size 0.1524 0.1524)
			(layers "F.Cu" "F.Mask" "F.Paste")
			(net "VREF7")
			(options
				(clearance outline)
				(anchor circle)
			)
			(primitives
				(gr_poly
					(pts
						(arc
							(start 0.3048 -0.2032)
							(mid 0.275042 -0.275042)
							(end 0.2032 -0.3048)
						)
						(arc
							(start -0.2032 -0.3048)
							(mid -0.275042 -0.275042)
							(end -0.3048 -0.2032)
						)
						(arc
							(start -0.3048 0.2032)
							(mid -0.275042 0.275042)
							(end -0.2032 0.3048)
						)
						(arc
							(start 0.2032 0.3048)
							(mid 0.275042 0.275042)
							(end 0.3048 0.2032)
						)
					)
					(width 0)
					(fill yes)
				)
			)
		)
		(pad "2" smd custom
			(at 0 0.4445 270)
			(size 0.1524 0.1524)
			(layers "F.Cu" "F.Mask" "F.Paste")
			(net "GND")
			(options
				(clearance outline)
				(anchor circle)
			)
			(primitives
				(gr_poly
					(pts
						(arc
							(start 0.3048 -0.2032)
							(mid 0.275042 -0.275042)
							(end 0.2032 -0.3048)
						)
						(arc
							(start -0.2032 -0.3048)
							(mid -0.275042 -0.275042)
							(end -0.3048 -0.2032)
						)
						(arc
							(start -0.3048 0.2032)
							(mid -0.275042 0.275042)
							(end -0.2032 0.3048)
						)
						(arc
							(start 0.2032 0.3048)
							(mid 0.275042 0.275042)
							(end 0.3048 0.2032)
						)
					)
					(width 0)
					(fill yes)
				)
			)
		)
	)
)
